# TIMECARD (Time Appliance Project (Time Card)) — schematic netlist excerpt (pin names and nets, part order shuffled) for the footprints in the layout excerpt that follows; sources: Cadence DE-HDL packaged netlist, KiCad conversion of R4006-B0001-02_R01.brd

U19  24LC16BT_I_ST_TSSOP8  pkg SOP8_173X118_P0256  page 16
  A0  = UNNAMED_5_24LC16BTISTTSSOP8_I15
  A1  = UNNAMED_5_24LC16BTISTTSSOP8_I_1
  A2  = UNNAMED_5_24LC16BTISTTSSOP8_I_2
  VSS  = SG
  SDA  = SEC_EEPROM_SDA
  SCL  = EEPROM_SCL
  WP  = SEC_EEPROM_WP
  VCC  = XP3R3V_FPGA

TP62  TP_PIONT  pkg TP010CT020B030_PTH  page 25 : \1\ = R_MAC_BITEOUT

(kicad_pcb
	(version 20260206)
	(generator "pcbnew")
	(generator_version "10.0")
	(general
		(thickness 1.6)
		(legacy_teardrops no)
	)
	(paper "A4")
	(title_block
		(title "timecard-production-celestica-r4006 — R4006-B0001-02_R01.brd")
		(comment 1 "Time Appliance Project (Time Card) / footprints 118-119 of 1113")
	)
	(layers
		(0 "F.Cu" signal "TOP")
		(4 "In1.Cu" signal "L02_GND1")
		(6 "In2.Cu" signal "L03_SIG1")
		(8 "In3.Cu" signal "L04_GND2")
		(10 "In4.Cu" signal "L05_VCC1")
		(12 "In5.Cu" signal "L06_VCC2")
		(14 "In6.Cu" signal "L07_GND3")
		(16 "In7.Cu" signal "L08_SIG2")
		(18 "In8.Cu" signal "L09_GND4")
		(2 "B.Cu" signal "BOTTOM")
		(9 "F.Adhes" user "F.Adhesive")
		(11 "B.Adhes" user "B.Adhesive")
		(13 "F.Paste" user "Package Geometry/Pastemask Top")
		(15 "B.Paste" user "Package Geometry/Pastemask Bottom")
		(5 "F.SilkS" user "Ref Des/Silkscreen Top")
		(7 "B.SilkS" user "Ref Des/Silkscreen Bottom")
		(1 "F.Mask" user "Board Geometry/Soldermask Top")
		(3 "B.Mask" user "Board Geometry/Soldermask Bottom")
		(17 "Dwgs.User" user "User.Drawings")
		(19 "Cmts.User" user "User.Comments")
		(21 "Eco1.User" user "User.Eco1")
		(23 "Eco2.User" user "User.Eco2")
		(25 "Edge.Cuts" user "Board Geometry/Outline")
		(27 "Margin" user)
		(31 "F.CrtYd" user "Package Geometry/Place Bound Top")
		(29 "B.CrtYd" user "Package Geometry/Place Bound Bottom")
		(35 "F.Fab" user "Ref Des/Assembly Top")
		(33 "B.Fab" user "Ref Des/Assembly Bottom")
	)
	(footprint ""
		(layer "F.Cu")
		(at 126.238 -39.116)
		(property "Reference" "TP62"
			(at -0.60325 0.5334 90)
			(unlocked yes)
			(layer "F.SilkS")
			(effects
				(font
					(size 0.635 0.4064)
					(thickness 0.1524)
				)
				(justify left)
			)
		)
		(property "Value" ""
			(at 0 0 0)
			(layer "F.Fab")
			(effects
				(font
					(size 1.27 1.27)
				)
			)
		)
		(property "Device Type" "TP_PIONT-TP010CT020B030_PTH-TPA"
			(at -1.341882 0.996696 0)
			(unlocked yes)
			(layer "F.Fab")
			(hide yes)
			(effects
				(font
					(size 0.7874 0.5842)
					(thickness 0.000001)
				)
				(justify left)
			)
		)
		(duplicate_pad_numbers_are_jumpers no)
		(fp_poly
			(pts
				(arc
					(start 0.889 0)
					(mid -0.889 0)
					(end 0.889 0)
				)
			)
			(stroke
				(width 0)
				(type default)
			)
			(fill no)
			(layer "B.CrtYd")
		)
		(fp_poly
			(pts
				(arc
					(start 0.889 0)
					(mid -0.889 0)
					(end 0.889 0)
				)
			)
			(stroke
				(width 0)
				(type default)
			)
			(fill no)
			(layer "F.CrtYd")
		)
		(pad "1" thru_hole circle
			(at 0 0)
			(size 0.508 0.508)
			(drill 0.254)
			(layers "*.Cu" "*.Mask")
			(remove_unused_layers no)
			(net "R_MAC_BITEOUT")
			(clearance 0.1016)
			(padstack
				(mode front_inner_back)
				(layer "Inner"
					(shape circle)
					(size 0.508 0.508)
					(clearance 0.1016)
				)
				(layer "B.Cu"
					(shape circle)
					(size 0.762 0.762)
					(clearance -0.0254)
				)
			)
		)
	)
	(footprint ""
		(layer "F.Cu")
		(at 19.685 -21.0312 -90)
		(property "Reference" "U19"
			(at -1.9558 -2.70637 90)
			(unlocked yes)
			(layer "F.SilkS")
			(effects
				(font
					(size 0.7874 0.5842)
					(thickness 0.1524)
				)
			)
		)
		(property "Value" ""
			(at 0 0 270)
			(layer "F.Fab")
			(effects
				(font
					(size 1.27 1.27)
				)
			)
		)
		(property "Device Type" "24LC16BT_I_ST_TSSOP8-G221-1017A"
			(at 0.0254 2.56667 270)
			(unlocked yes)
			(layer "F.Fab")
			(hide yes)
			(effects
				(font
					(size 0.7874 0.5842)
					(thickness 0.000001)
				)
			)
		)
		(property "User Part Number" "PARTNUM*"
			(at 0 3.45567 270)
			(unlocked yes)
			(layer "Cmts.User")
			(hide yes)
			(effects
				(font
					(size 0.7874 0.5842)
					(thickness 0.000001)
				)
			)
		)
		(duplicate_pad_numbers_are_jumpers no)
		(fp_line
			(start -4.0767 1.8034)
			(end -4.0767 -1.8034)
			(stroke
				(width 0.1)
				(type default)
			)
			(layer "F.SilkS")
		)
		(fp_line
			(start 4.0767 1.8034)
			(end -4.0767 1.8034)
			(stroke
				(width 0.1)
				(type default)
			)
			(layer "F.SilkS")
		)
		(fp_line
			(start -4.0767 -1.8034)
			(end 4.0767 -1.8034)
			(stroke
				(width 0.1)
				(type default)
			)
			(layer "F.SilkS")
		)
		(fp_line
			(start 4.0767 -1.8034)
			(end 4.0767 1.8034)
			(stroke
				(width 0.1)
				(type default)
			)
			(layer "F.SilkS")
		)
		(fp_poly
			(pts
				(arc
					(start -4.1148 -2.794)
					(mid -4.1148 -2.032)
					(end -4.1148 -2.794)
				)
			)
			(stroke
				(width 0)
				(type default)
			)
			(fill yes)
			(layer "F.SilkS")
		)
		(fp_poly
			(pts
				(xy -4.3307 2.0574) (xy 4.3307 2.0574) (xy 4.3307 -2.0574) (xy -4.3307 -2.0574)
			)
			(stroke
				(width 0)
				(type default)
			)
			(fill no)
			(layer "F.CrtYd")
		)
		(fp_line
			(start -2.2479 1.5494)
			(end -2.2479 -1.5494)
			(stroke
				(width 0.1)
				(type default)
			)
			(layer "F.Fab")
		)
		(fp_line
			(start 2.2479 1.5494)
			(end -2.2479 1.5494)
			(stroke
				(width 0.1)
				(type default)
			)
			(layer "F.Fab")
		)
		(fp_line
			(start -2.2479 -1.5494)
			(end 2.2479 -1.5494)
			(stroke
				(width 0.1)
				(type default)
			)
			(layer "F.Fab")
		)
		(fp_line
			(start 2.2479 -1.5494)
			(end 2.2479 1.5494)
			(stroke
				(width 0.1)
				(type default)
			)
			(layer "F.Fab")
		)
		(fp_poly
			(pts
				(arc
					(start -1.778 -1.397)
					(mid -1.778 -0.635)
					(end -1.778 -1.397)
				)
			)
			(stroke
				(width 0)
				(type default)
			)
			(fill yes)
			(layer "F.Fab")
		)
		(fp_text user "5"
			(at 5.01015 1.9431 0)
			(unlocked yes)
			(layer "F.SilkS")
			(effects
				(font
					(size 0.635 0.4064)
					(thickness 0.1524)
				)
				(justify left)
			)
		)
		(fp_text user "4"
			(at -4.76885 1.8161 0)
			(unlocked yes)
			(layer "F.SilkS")
			(effects
				(font
					(size 0.635 0.4064)
					(thickness 0.1524)
				)
				(justify left)
			)
		)
		(fp_text user "8"
			(at 3.61315 -2.1209 0)
			(unlocked yes)
			(layer "F.SilkS")
			(effects
				(font
					(size 0.635 0.4064)
					(thickness 0.1524)
				)
				(justify left)
			)
		)
		(fp_text user "5"
			(at 4.826 1.294384 90)
			(unlocked yes)
			(layer "F.Fab")
			(effects
				(font
					(size 0.7874 0.5842)
					(thickness 0.1524)
				)
				(justify left)
			)
		)
		(fp_text user "4"
			(at -4.6736 1.218184 90)
			(unlocked yes)
			(layer "F.Fab")
			(effects
				(font
					(size 0.7874 0.5842)
					(thickness 0.1524)
				)
				(justify left)
			)
		)
		(fp_text user "8"
			(at 4.826 -0.813816 90)
			(unlocked yes)
			(layer "F.Fab")
			(effects
				(font
					(size 0.7874 0.5842)
					(thickness 0.1524)
				)
				(justify left)
			)
		)
		(pad "1" smd rect
			(at -3.0353 -0.975106 270)
			(size 1.5748 0.3556)
			(layers "F.Cu" "F.Mask" "F.Paste")
			(net "UNNAMED_5_24LC16BTISTTSSOP8_I15")
		)
		(pad "2" smd rect
			(at -3.0353 -0.32512 270)
			(size 1.5748 0.3556)
			(layers "F.Cu" "F.Mask" "F.Paste")
			(net "UNNAMED_5_24LC16BTISTTSSOP8_I_1")
		)
		(pad "3" smd rect
			(at -3.0353 0.324866 270)
			(size 1.5748 0.3556)
			(layers "F.Cu" "F.Mask" "F.Paste")
			(net "UNNAMED_5_24LC16BTISTTSSOP8_I_2")
		)
		(pad "4" smd rect
			(at -3.0353 0.974852 270)
			(size 1.5748 0.3556)
			(layers "F.Cu" "F.Mask" "F.Paste")
			(net "SG")
		)
		(pad "5" smd rect
			(at 3.0353 0.974852 270)
			(size 1.5748 0.3556)
			(layers "F.Cu" "F.Mask" "F.Paste")
			(net "SEC_EEPROM_SDA")
		)
		(pad "6" smd rect
			(at 3.0353 0.324866 270)
			(size 1.5748 0.3556)
			(layers "F.Cu" "F.Mask" "F.Paste")
			(net "EEPROM_SCL")
		)
		(pad "7" smd rect
			(at 3.0353 -0.32512 270)
			(size 1.5748 0.3556)
			(layers "F.Cu" "F.Mask" "F.Paste")
			(net "SEC_EEPROM_WP")
		)
		(pad "8" smd rect
			(at 3.0353 -0.975106 270)
			(size 1.5748 0.3556)
			(layers "F.Cu" "F.Mask" "F.Paste")
			(net "XP3R3V_FPGA")
		)
	)
)
